(kicad_pcb
	(version 20260206)
	(generator "pcbnew")
	(generator_version "10.0")
	(general
		(thickness 1.6)
		(legacy_teardrops no)
	)
	(paper "A4")
	(title_block
		(title "01162023_DA0F0TEBIF0_F0T_Expander_BD_F_brd_V02_OCP.brd")
		(comment 1 "Grand Teton / footprints 7936-7942 of 9728")
	)
	(layers
		(0 "F.Cu" signal "TOP")
		(4 "In1.Cu" signal "GND")
		(6 "In2.Cu" signal "VCC")
		(8 "In3.Cu" signal "VCC1")
		(10 "In4.Cu" signal "GND1")
		(12 "In5.Cu" signal "IN1")
		(14 "In6.Cu" signal "GND2")
		(16 "In7.Cu" signal "IN2")
		(18 "In8.Cu" signal "GND3")
		(20 "In9.Cu" signal "IN3")
		(22 "In10.Cu" signal "GND4")
		(24 "In11.Cu" signal "IN4")
		(26 "In12.Cu" signal "GND5")
		(28 "In13.Cu" signal "IN5")
		(30 "In14.Cu" signal "GND6")
		(32 "In15.Cu" signal "IN6")
		(34 "In16.Cu" signal "GND7")
		(2 "B.Cu" signal "BOTTOM")
		(9 "F.Adhes" user "F.Adhesive")
		(11 "B.Adhes" user "B.Adhesive")
		(13 "F.Paste" user "Package Geometry/Pastemask Top")
		(15 "B.Paste" user "Package Geometry/Pastemask Bottom")
		(5 "F.SilkS" user "Ref Des/Silkscreen Top")
		(7 "B.SilkS" user "Ref Des/Silkscreen Bottom")
		(1 "F.Mask" user "Board Geometry/Soldermask Top")
		(3 "B.Mask" user "Board Geometry/Soldermask Bottom")
		(17 "Dwgs.User" user "User.Drawings")
		(19 "Cmts.User" user "User.Comments")
		(21 "Eco1.User" user "User.Eco1")
		(23 "Eco2.User" user "User.Eco2")
		(25 "Edge.Cuts" user "Board Geometry/Outline")
		(27 "Margin" user)
		(31 "F.CrtYd" user "Package Geometry/Place Bound Top")
		(29 "B.CrtYd" user "Package Geometry/Place Bound Bottom")
		(35 "F.Fab" user "Ref Des/Assembly Top")
		(33 "B.Fab" user "Ref Des/Assembly Bottom")
	)
	(footprint ""
		(layer "B.Cu")
		(at 16.257778 -310.154066 90)
		(property "Reference" "R4435"
			(at 0 0 90)
			(layer "B.SilkS")
			(hide yes)
			(effects
				(font
					(size 1.27 1.27)
				)
				(justify mirror)
			)
		)
		(property "Value" ""
			(at 0 0 90)
			(layer "B.Fab")
			(effects
				(font
					(size 1.27 1.27)
				)
				(justify mirror)
			)
		)
		(duplicate_pad_numbers_are_jumpers no)
		(fp_line
			(start 0.7874 -0.4064)
			(end -0.7874 -0.4064)
			(stroke
				(width 0.1524)
				(type default)
			)
			(layer "B.SilkS")
		)
		(fp_line
			(start -0.7874 -0.4064)
			(end -0.7874 0.4064)
			(stroke
				(width 0.1524)
				(type default)
			)
			(layer "B.SilkS")
		)
		(fp_line
			(start 0.7874 0.4064)
			(end 0.7874 -0.4064)
			(stroke
				(width 0.1524)
				(type default)
			)
			(layer "B.SilkS")
		)
		(fp_line
			(start -0.7874 0.4064)
			(end 0.7874 0.4064)
			(stroke
				(width 0.1524)
				(type default)
			)
			(layer "B.SilkS")
		)
		(fp_line
			(start 0.67945 -0.305054)
			(end 0.12065 -0.305054)
			(stroke
				(width 0.1)
				(type default)
			)
			(layer "B.Fab")
		)
		(fp_line
			(start 0.12065 -0.305054)
			(end 0.12065 -0.2794)
			(stroke
				(width 0.1)
				(type default)
			)
			(layer "B.Fab")
		)
		(fp_line
			(start -0.12065 -0.3048)
			(end -0.67945 -0.3048)
			(stroke
				(width 0.1)
				(type default)
			)
			(layer "B.Fab")
		)
		(fp_line
			(start -0.67945 -0.3048)
			(end -0.67945 0.3048)
			(stroke
				(width 0.1)
				(type default)
			)
			(layer "B.Fab")
		)
		(fp_line
			(start 0.12065 -0.2794)
			(end -0.12065 -0.2794)
			(stroke
				(width 0.1)
				(type default)
			)
			(layer "B.Fab")
		)
		(fp_line
			(start -0.12065 -0.2794)
			(end -0.12065 -0.3048)
			(stroke
				(width 0.1)
				(type default)
			)
			(layer "B.Fab")
		)
		(fp_line
			(start 0.12065 0.2794)
			(end 0.12065 0.3048)
			(stroke
				(width 0.1)
				(type default)
			)
			(layer "B.Fab")
		)
		(fp_line
			(start -0.120396 0.2794)
			(end 0.12065 0.2794)
			(stroke
				(width 0.1)
				(type default)
			)
			(layer "B.Fab")
		)
		(fp_line
			(start 0.67945 0.3048)
			(end 0.67945 -0.305054)
			(stroke
				(width 0.1)
				(type default)
			)
			(layer "B.Fab")
		)
		(fp_line
			(start 0.12065 0.3048)
			(end 0.67945 0.3048)
			(stroke
				(width 0.1)
				(type default)
			)
			(layer "B.Fab")
		)
		(fp_line
			(start -0.120396 0.3048)
			(end -0.120396 0.2794)
			(stroke
				(width 0.1)
				(type default)
			)
			(layer "B.Fab")
		)
		(fp_line
			(start -0.67945 0.3048)
			(end -0.120396 0.3048)
			(stroke
				(width 0.1)
				(type default)
			)
			(layer "B.Fab")
		)
		(pad "1" smd circle
			(at 0.40005 0 270)
			(size 0 0)
			(layers "B.Cu" "B.Mask" "B.Paste")
			(net "PWRGD_P1V25_PEX0_R")
		)
		(pad "2" smd circle
			(at -0.40005 0 270)
			(size 0 0)
			(layers "B.Cu" "B.Mask" "B.Paste")
			(net "PWRGD_P1V25_PEX0")
		)
	)
	(footprint ""
		(layer "B.Cu")
		(at 156.273754 -296.9514 180)
		(property "Reference" "R3455"
			(at 0 0 0)
			(layer "B.SilkS")
			(hide yes)
			(effects
				(font
					(size 1.27 1.27)
				)
				(justify mirror)
			)
		)
		(property "Value" ""
			(at 0 0 0)
			(layer "B.Fab")
			(effects
				(font
					(size 1.27 1.27)
				)
				(justify mirror)
			)
		)
		(duplicate_pad_numbers_are_jumpers no)
		(fp_line
			(start 0.7874 0.4064)
			(end 0.7874 -0.4064)
			(stroke
				(width 0.1524)
				(type default)
			)
			(layer "B.SilkS")
		)
		(fp_line
			(start 0.7874 -0.4064)
			(end -0.7874 -0.4064)
			(stroke
				(width 0.1524)
				(type default)
			)
			(layer "B.SilkS")
		)
		(fp_line
			(start -0.7874 0.4064)
			(end 0.7874 0.4064)
			(stroke
				(width 0.1524)
				(type default)
			)
			(layer "B.SilkS")
		)
		(fp_line
			(start -0.7874 -0.4064)
			(end -0.7874 0.4064)
			(stroke
				(width 0.1524)
				(type default)
			)
			(layer "B.SilkS")
		)
		(fp_line
			(start 0.67945 0.3048)
			(end 0.67945 -0.305054)
			(stroke
				(width 0.1)
				(type default)
			)
			(layer "B.Fab")
		)
		(fp_line
			(start 0.67945 -0.305054)
			(end 0.12065 -0.305054)
			(stroke
				(width 0.1)
				(type default)
			)
			(layer "B.Fab")
		)
		(fp_line
			(start 0.12065 0.3048)
			(end 0.67945 0.3048)
			(stroke
				(width 0.1)
				(type default)
			)
			(layer "B.Fab")
		)
		(fp_line
			(start 0.12065 0.2794)
			(end 0.12065 0.3048)
			(stroke
				(width 0.1)
				(type default)
			)
			(layer "B.Fab")
		)
		(fp_line
			(start 0.12065 -0.2794)
			(end -0.12065 -0.2794)
			(stroke
				(width 0.1)
				(type default)
			)
			(layer "B.Fab")
		)
		(fp_line
			(start 0.12065 -0.305054)
			(end 0.12065 -0.2794)
			(stroke
				(width 0.1)
				(type default)
			)
			(layer "B.Fab")
		)
		(fp_line
			(start -0.120396 0.3048)
			(end -0.120396 0.2794)
			(stroke
				(width 0.1)
				(type default)
			)
			(layer "B.Fab")
		)
		(fp_line
			(start -0.120396 0.2794)
			(end 0.12065 0.2794)
			(stroke
				(width 0.1)
				(type default)
			)
			(layer "B.Fab")
		)
		(fp_line
			(start -0.12065 -0.2794)
			(end -0.12065 -0.3048)
			(stroke
				(width 0.1)
				(type default)
			)
			(layer "B.Fab")
		)
		(fp_line
			(start -0.12065 -0.3048)
			(end -0.67945 -0.3048)
			(stroke
				(width 0.1)
				(type default)
			)
			(layer "B.Fab")
		)
		(fp_line
			(start -0.67945 0.3048)
			(end -0.120396 0.3048)
			(stroke
				(width 0.1)
				(type default)
			)
			(layer "B.Fab")
		)
		(fp_line
			(start -0.67945 -0.3048)
			(end -0.67945 0.3048)
			(stroke
				(width 0.1)
				(type default)
			)
			(layer "B.Fab")
		)
		(pad "1" smd circle
			(at 0.40005 0)
			(size 0 0)
			(layers "B.Cu" "B.Mask" "B.Paste")
			(net "SPI_PEX1_SDIO1_R")
		)
		(pad "2" smd circle
			(at -0.40005 0)
			(size 0 0)
			(layers "B.Cu" "B.Mask" "B.Paste")
			(net "SPI_PEX1_SDIO1")
		)
	)
	(footprint ""
		(layer "B.Cu")
		(at 410.799788 -303.499774 -90)
		(property "Reference" "C3429"
			(at 0 0 90)
			(layer "B.SilkS")
			(hide yes)
			(effects
				(font
					(size 1.27 1.27)
				)
				(justify mirror)
			)
		)
		(property "Value" ""
			(at 0 0 90)
			(layer "B.Fab")
			(effects
				(font
					(size 1.27 1.27)
				)
				(justify mirror)
			)
		)
		(duplicate_pad_numbers_are_jumpers no)
		(fp_line
			(start -0.299974 0.150114)
			(end 0.299974 0.150114)
			(stroke
				(width 0.1)
				(type default)
			)
			(layer "B.Fab")
		)
		(fp_line
			(start 0.299974 0.150114)
			(end 0.299974 -0.150114)
			(stroke
				(width 0.1)
				(type default)
			)
			(layer "B.Fab")
		)
		(fp_line
			(start -0.299974 -0.150114)
			(end -0.299974 0.150114)
			(stroke
				(width 0.1)
				(type default)
			)
			(layer "B.Fab")
		)
		(fp_line
			(start 0.299974 -0.150114)
			(end -0.299974 -0.150114)
			(stroke
				(width 0.1)
				(type default)
			)
			(layer "B.Fab")
		)
		(pad "1" smd rect
			(at 0.2667 0 90)
			(size 0.3048 0.381)
			(layers "B.Cu" "B.Mask" "B.Paste")
			(net "P1V25_PEX3")
		)
		(pad "2" smd rect
			(at -0.2667 0 90)
			(size 0.3048 0.381)
			(layers "B.Cu" "B.Mask" "B.Paste")
			(net "GND")
		)
	)
	(footprint ""
		(layer "B.Cu")
		(at 410.799788 -301.599854 -90)
		(property "Reference" "C1967"
			(at 0 0 90)
			(layer "B.SilkS")
			(hide yes)
			(effects
				(font
					(size 1.27 1.27)
				)
				(justify mirror)
			)
		)
		(property "Value" ""
			(at 0 0 90)
			(layer "B.Fab")
			(effects
				(font
					(size 1.27 1.27)
				)
				(justify mirror)
			)
		)
		(duplicate_pad_numbers_are_jumpers no)
		(fp_line
			(start -0.299974 0.150114)
			(end 0.299974 0.150114)
			(stroke
				(width 0.1)
				(type default)
			)
			(layer "B.Fab")
		)
		(fp_line
			(start 0.299974 0.150114)
			(end 0.299974 -0.150114)
			(stroke
				(width 0.1)
				(type default)
			)
			(layer "B.Fab")
		)
		(fp_line
			(start -0.299974 -0.150114)
			(end -0.299974 0.150114)
			(stroke
				(width 0.1)
				(type default)
			)
			(layer "B.Fab")
		)
		(fp_line
			(start 0.299974 -0.150114)
			(end -0.299974 -0.150114)
			(stroke
				(width 0.1)
				(type default)
			)
			(layer "B.Fab")
		)
		(pad "1" smd rect
			(at 0.2667 0 90)
			(size 0.3048 0.381)
			(layers "B.Cu" "B.Mask" "B.Paste")
			(net "P0V8_SERDES_VDDA_PEX3")
		)
		(pad "2" smd rect
			(at -0.2667 0 90)
			(size 0.3048 0.381)
			(layers "B.Cu" "B.Mask" "B.Paste")
			(net "GND")
		)
	)
	(footprint ""
		(layer "B.Cu")
		(at 357.770684 -283.818584 90)
		(property "Reference" "PR156"
			(at 0 0 90)
			(layer "B.SilkS")
			(hide yes)
			(effects
				(font
					(size 1.27 1.27)
				)
				(justify mirror)
			)
		)
		(property "Value" ""
			(at 0 0 90)
			(layer "B.Fab")
			(effects
				(font
					(size 1.27 1.27)
				)
				(justify mirror)
			)
		)
		(duplicate_pad_numbers_are_jumpers no)
		(fp_line
			(start 0.7874 -0.4064)
			(end -0.7874 -0.4064)
			(stroke
				(width 0.1524)
				(type default)
			)
			(layer "B.SilkS")
		)
		(fp_line
			(start -0.7874 -0.4064)
			(end -0.7874 0.4064)
			(stroke
				(width 0.1524)
				(type default)
			)
			(layer "B.SilkS")
		)
		(fp_line
			(start 0.7874 0.4064)
			(end 0.7874 -0.4064)
			(stroke
				(width 0.1524)
				(type default)
			)
			(layer "B.SilkS")
		)
		(fp_line
			(start -0.7874 0.4064)
			(end 0.7874 0.4064)
			(stroke
				(width 0.1524)
				(type default)
			)
			(layer "B.SilkS")
		)
		(fp_line
			(start 0.67945 -0.305054)
			(end 0.12065 -0.305054)
			(stroke
				(width 0.1)
				(type default)
			)
			(layer "B.Fab")
		)
		(fp_line
			(start 0.12065 -0.305054)
			(end 0.12065 -0.2794)
			(stroke
				(width 0.1)
				(type default)
			)
			(layer "B.Fab")
		)
		(fp_line
			(start -0.12065 -0.3048)
			(end -0.67945 -0.3048)
			(stroke
				(width 0.1)
				(type default)
			)
			(layer "B.Fab")
		)
		(fp_line
			(start -0.67945 -0.3048)
			(end -0.67945 0.3048)
			(stroke
				(width 0.1)
				(type default)
			)
			(layer "B.Fab")
		)
		(fp_line
			(start 0.12065 -0.2794)
			(end -0.12065 -0.2794)
			(stroke
				(width 0.1)
				(type default)
			)
			(layer "B.Fab")
		)
		(fp_line
			(start -0.12065 -0.2794)
			(end -0.12065 -0.3048)
			(stroke
				(width 0.1)
				(type default)
			)
			(layer "B.Fab")
		)
		(fp_line
			(start 0.12065 0.2794)
			(end 0.12065 0.3048)
			(stroke
				(width 0.1)
				(type default)
			)
			(layer "B.Fab")
		)
		(fp_line
			(start -0.120396 0.2794)
			(end 0.12065 0.2794)
			(stroke
				(width 0.1)
				(type default)
			)
			(layer "B.Fab")
		)
		(fp_line
			(start 0.67945 0.3048)
			(end 0.67945 -0.305054)
			(stroke
				(width 0.1)
				(type default)
			)
			(layer "B.Fab")
		)
		(fp_line
			(start 0.12065 0.3048)
			(end 0.67945 0.3048)
			(stroke
				(width 0.1)
				(type default)
			)
			(layer "B.Fab")
		)
		(fp_line
			(start -0.120396 0.3048)
			(end -0.120396 0.2794)
			(stroke
				(width 0.1)
				(type default)
			)
			(layer "B.Fab")
		)
		(fp_line
			(start -0.67945 0.3048)
			(end -0.120396 0.3048)
			(stroke
				(width 0.1)
				(type default)
			)
			(layer "B.Fab")
		)
		(pad "1" smd circle
			(at 0.40005 0 270)
			(size 0 0)
			(layers "B.Cu" "B.Mask" "B.Paste")
			(net "P0V8_PEX3_PVCC")
		)
		(pad "2" smd circle
			(at -0.40005 0 270)
			(size 0 0)
			(layers "B.Cu" "B.Mask" "B.Paste")
			(net "P0V8_PEX3_VCC1")
		)
	)
	(footprint ""
		(layer "B.Cu")
		(at 108.711238 -285.576518 -90)
		(property "Reference" "PR7176"
			(at 0 0 90)
			(layer "B.SilkS")
			(hide yes)
			(effects
				(font
					(size 1.27 1.27)
				)
				(justify mirror)
			)
		)
		(property "Value" ""
			(at 0 0 90)
			(layer "B.Fab")
			(effects
				(font
					(size 1.27 1.27)
				)
				(justify mirror)
			)
		)
		(duplicate_pad_numbers_are_jumpers no)
		(fp_line
			(start -0.7874 0.4064)
			(end 0.7874 0.4064)
			(stroke
				(width 0.1524)
				(type default)
			)
			(layer "B.SilkS")
		)
		(fp_line
			(start 0.7874 0.4064)
			(end 0.7874 -0.4064)
			(stroke
				(width 0.1524)
				(type default)
			)
			(layer "B.SilkS")
		)
		(fp_line
			(start -0.7874 -0.4064)
			(end -0.7874 0.4064)
			(stroke
				(width 0.1524)
				(type default)
			)
			(layer "B.SilkS")
		)
		(fp_line
			(start 0.7874 -0.4064)
			(end -0.7874 -0.4064)
			(stroke
				(width 0.1524)
				(type default)
			)
			(layer "B.SilkS")
		)
		(fp_line
			(start -0.67945 0.3048)
			(end -0.120396 0.3048)
			(stroke
				(width 0.1)
				(type default)
			)
			(layer "B.Fab")
		)
		(fp_line
			(start -0.120396 0.3048)
			(end -0.120396 0.2794)
			(stroke
				(width 0.1)
				(type default)
			)
			(layer "B.Fab")
		)
		(fp_line
			(start 0.12065 0.3048)
			(end 0.67945 0.3048)
			(stroke
				(width 0.1)
				(type default)
			)
			(layer "B.Fab")
		)
		(fp_line
			(start 0.67945 0.3048)
			(end 0.67945 -0.305054)
			(stroke
				(width 0.1)
				(type default)
			)
			(layer "B.Fab")
		)
		(fp_line
			(start -0.120396 0.2794)
			(end 0.12065 0.2794)
			(stroke
				(width 0.1)
				(type default)
			)
			(layer "B.Fab")
		)
		(fp_line
			(start 0.12065 0.2794)
			(end 0.12065 0.3048)
			(stroke
				(width 0.1)
				(type default)
			)
			(layer "B.Fab")
		)
		(fp_line
			(start -0.12065 -0.2794)
			(end -0.12065 -0.3048)
			(stroke
				(width 0.1)
				(type default)
			)
			(layer "B.Fab")
		)
		(fp_line
			(start 0.12065 -0.2794)
			(end -0.12065 -0.2794)
			(stroke
				(width 0.1)
				(type default)
			)
			(layer "B.Fab")
		)
		(fp_line
			(start -0.67945 -0.3048)
			(end -0.67945 0.3048)
			(stroke
				(width 0.1)
				(type default)
			)
			(layer "B.Fab")
		)
		(fp_line
			(start -0.12065 -0.3048)
			(end -0.67945 -0.3048)
			(stroke
				(width 0.1)
				(type default)
			)
			(layer "B.Fab")
		)
		(fp_line
			(start 0.12065 -0.305054)
			(end 0.12065 -0.2794)
			(stroke
				(width 0.1)
				(type default)
			)
			(layer "B.Fab")
		)
		(fp_line
			(start 0.67945 -0.305054)
			(end 0.12065 -0.305054)
			(stroke
				(width 0.1)
				(type default)
			)
			(layer "B.Fab")
		)
		(pad "1" smd circle
			(at 0.40005 0 90)
			(size 0 0)
			(layers "B.Cu" "B.Mask" "B.Paste")
			(net "P0V8_PEX0_PVCC")
		)
		(pad "2" smd circle
			(at -0.40005 0 90)
			(size 0 0)
			(layers "B.Cu" "B.Mask" "B.Paste")
			(net "P3V3_AUX")
		)
	)
	(footprint ""
		(layer "B.Cu")
		(at 449.83781 -275.872956)
		(property "Reference" "C4387"
			(at 0 0 0)
			(layer "B.SilkS")
			(hide yes)
			(effects
				(font
					(size 1.27 1.27)
				)
				(justify mirror)
			)
		)
		(property "Value" ""
			(at 0 0 0)
			(layer "B.Fab")
			(effects
				(font
					(size 1.27 1.27)
				)
				(justify mirror)
			)
		)
		(duplicate_pad_numbers_are_jumpers no)
		(fp_line
			(start -1.2954 -0.5842)
			(end -1.2954 0.5842)
			(stroke
				(width 0.1524)
				(type default)
			)
			(layer "B.SilkS")
		)
		(fp_line
			(start -1.2954 0.5842)
			(end 1.2954 0.5842)
			(stroke
				(width 0.1524)
				(type default)
			)
			(layer "B.SilkS")
		)
		(fp_line
			(start 1.2954 -0.5842)
			(end -1.2954 -0.5842)
			(stroke
				(width 0.1524)
				(type default)
			)
			(layer "B.SilkS")
		)
		(fp_line
			(start 1.2954 0.5842)
			(end 1.2954 -0.5842)
			(stroke
				(width 0.1524)
				(type default)
			)
			(layer "B.SilkS")
		)
		(fp_line
			(start -1.1938 -0.4064)
			(end -1.1938 0.4064)
			(stroke
				(width 0.1)
				(type default)
			)
			(layer "B.Fab")
		)
		(fp_line
			(start -1.1938 0.4064)
			(end -0.8636 0.4064)
			(stroke
				(width 0.1)
				(type default)
			)
			(layer "B.Fab")
		)
		(fp_line
			(start -0.8636 -0.4572)
			(end -0.8636 -0.4064)
			(stroke
				(width 0.1)
				(type default)
			)
			(layer "B.Fab")
		)
		(fp_line
			(start -0.8636 -0.4064)
			(end -1.1938 -0.4064)
			(stroke
				(width 0.1)
				(type default)
			)
			(layer "B.Fab")
		)
		(fp_line
			(start -0.8636 0.4064)
			(end -0.8636 0.4572)
			(stroke
				(width 0.1)
				(type default)
			)
			(layer "B.Fab")
		)
		(fp_line
			(start -0.8636 0.4572)
			(end 0.8636 0.4572)
			(stroke
				(width 0.1)
				(type default)
			)
			(layer "B.Fab")
		)
		(fp_line
			(start 0.8636 -0.4572)
			(end -0.8636 -0.4572)
			(stroke
				(width 0.1)
				(type default)
			)
			(layer "B.Fab")
		)
		(fp_line
			(start 0.8636 -0.4064)
			(end 0.8636 -0.4572)
			(stroke
				(width 0.1)
				(type default)
			)
			(layer "B.Fab")
		)
		(fp_line
			(start 0.8636 0.4064)
			(end 1.1938 0.4064)
			(stroke
				(width 0.1)
				(type default)
			)
			(layer "B.Fab")
		)
		(fp_line
			(start 0.8636 0.4572)
			(end 0.8636 0.4064)
			(stroke
				(width 0.1)
				(type default)
			)
			(layer "B.Fab")
		)
		(fp_line
			(start 1.1938 -0.4064)
			(end 0.8636 -0.4064)
			(stroke
				(width 0.1)
				(type default)
			)
			(layer "B.Fab")
		)
		(fp_line
			(start 1.1938 0.4064)
			(end 1.1938 -0.4064)
			(stroke
				(width 0.1)
				(type default)
			)
			(layer "B.Fab")
		)
		(pad "1" smd rect
			(at 0.7366 0 270)
			(size 0.7112 0.8128)
			(layers "B.Cu" "B.Mask" "B.Paste")
			(net "P1V25_PEX3")
		)
		(pad "2" smd rect
			(at -0.7366 0 270)
			(size 0.7112 0.8128)
			(layers "B.Cu" "B.Mask" "B.Paste")
			(net "GND")
		)
	)
)
